FILE_TYPE = MACRO_DRAWING;
SET COLOR_WIRE YELLOW;
SET COLOR_PROP ORANGE;
SET COLOR_DOT WHITE;
SET COLOR_ARC YELLOW;
SET COLOR_BODY GREEN;
SET COLOR_NOTE PURPLE;
SET PROP_DISPLAY VALUE;
SET PAGE_NUMBER P130;
FORCEADD QUANTA_TITLE_BLOCK_C..1
(0 0);
FORCEPROP 1 LAST CUSTOM_TXT_CDS <NAME_2>
J 0
(-3175 50);
FORCEPROP 1 LAST CUSTOM_TXT_CDS <NAME_1>
J 0
(-3175 175);
FORCEPROP 1 LAST CUSTOM_TXT_CDS <Q_NUMBER>
J 0
(-1403 103);
DISPLAY 1.212766 (-1403 103);
FORCEPROP 1 LAST CUSTOM_TXT_CDS <Q_PROJ>
J 0
(-2382 102);
DISPLAY 1.212766 (-2382 102);
FORCEPROP 1 LAST CUSTOM_TXT_CDS <Q_REV>
J 0
(-184 103);
DISPLAY 1.212766 (-184 103);
FORCEPROP 1 LAST CUSTOM_TXT_CDS <CON_LAST_MODIFIED>
J 0
(-1885 15);
DISPLAY 0.978723 (-1885 15);
FORCEPROP 1 LAST CUSTOM_TXT_CDS <CON_PAGE_NUM> OF <CON_TOTAL_PAGES>
J 0
(-446 18);
DISPLAY 0.978723 (-446 18);
FORCEPROP 1 LAST Q_TITLE Blank
J 0
(-9275 50);
DISPLAY 2.446809 (-9275 50);
PAINT GREEN (-9275 50);
FORCEPROP 1 LAST Q_DEPT BU9
J 1
(-3763 49);
DISPLAY 1.957447 (-3763 49);
PAINT GREEN (-3763 49);
FORCEPROP 0 LAST CDS_CON_LAST_MODIFIED Wed Jul 21 11:36:33 2021
J 0
(-1885 15);
DISPLAY INVISIBLE (-1885 15);
FORCEPROP 1 LAST CDS_LMAN_SYM_OUTLINE -9475,6775,100,-125
J 0
(0 0);
DISPLAY 0.468085 (0 0);
PAINT GREEN (0 0);
DISPLAY INVISIBLE (0 0);
FORCEPROP 2 LAST CDS_LIB pure_quanta
J 0
(0 0);
DISPLAY INVISIBLE (0 0);
FORCEPROP 2 LAST PAGE_BORDER TRUE
J 0
(-7890 5250);
DISPLAY 0.638298 (-7890 5250);
PAINT PINK (-7890 5250);
DISPLAY INVISIBLE (-7890 5250);
FORCEPROP 1 LAST COMMENT_BODY TRUE
J 0
(12 -13);
DISPLAY 0.978723 (12 -13);
PAINT GREEN (12 -13);
DISPLAY INVISIBLE (12 -13);
FORCEPROP 2 LAST CUSTOM_TXT_CDS <XR_PAGE_TITLE>
J 0
(-7890 5250);
DISPLAY 0.638298 (-7890 5250);
PAINT PINK (-7890 5250);
DISPLAY INVISIBLE (-7890 5250);
FORCEPROP 2 LAST CDS_XR_PAGE_TITLE CR-130 : @T6G_MB_LIB.T6G(SCH_1):PAGE130
J 0
(-7890 5250);
DISPLAY 0.638298 (-7890 5250);
PAINT PINK (-7890 5250);
DISPLAY INVISIBLE (-7890 5250);
QUIT
